(kicad_pcb
	(version 20241229)
	(generator "pcbnew")
	(generator_version "9.0")
	(general
		(thickness 1.6642)
		(legacy_teardrops no)
	)
	(paper "A3")
	(title_block
		(title "PolarFire SoM")
		(date "2025-07-22")
		(rev "1.1.4")
		(company "Antmicro Ltd")
		(comment 1 "www.antmicro.com")
		(comment 9 "footprints 412-416 of 470")
	)
	(layers
		(0 "F.Cu" mixed)
		(4 "In1.Cu" power)
		(6 "In2.Cu" signal)
		(8 "In3.Cu" power)
		(10 "In4.Cu" signal)
		(12 "In5.Cu" power)
		(14 "In6.Cu" power)
		(16 "In7.Cu" signal)
		(18 "In8.Cu" power)
		(20 "In9.Cu" signal)
		(22 "In10.Cu" power)
		(24 "In11.Cu" signal)
		(26 "In12.Cu" signal)
		(2 "B.Cu" mixed)
		(9 "F.Adhes" user "F.Adhesive")
		(11 "B.Adhes" user "B.Adhesive")
		(13 "F.Paste" user)
		(15 "B.Paste" user)
		(5 "F.SilkS" user "F.Silkscreen")
		(7 "B.SilkS" user "B.Silkscreen")
		(1 "F.Mask" user)
		(3 "B.Mask" user)
		(17 "Dwgs.User" user "User.Drawings")
		(19 "Cmts.User" user "User.Comments")
		(21 "Eco1.User" user "User.Eco1")
		(23 "Eco2.User" user "User.Eco2")
		(25 "Edge.Cuts" user)
		(27 "Margin" user)
		(31 "F.CrtYd" user "F.Courtyard")
		(29 "B.CrtYd" user "B.Courtyard")
		(35 "F.Fab" user)
		(33 "B.Fab" user)
	)
	(footprint "antmicro-footprints:C_0402_1005Metric"
		(layer "B.Cu")
		(at 212.66 153 180)
		(descr "Capacitor SMD 0402")
		(tags "capacitor SMD 0402")
		(property "Reference" "C220"
			(at -2 -1.43 0)
			(layer "B.SilkS")
			(effects
				(font
					(size 0.7 0.7)
					(thickness 0.15)
				)
				(justify left bottom mirror)
			)
		)
		(property "Value" "C_100n_0402"
			(at -1.022927 -2.155213 0)
			(layer "B.Fab")
			(hide yes)
			(effects
				(font
					(size 0.7 0.7)
					(thickness 0.15)
				)
				(justify left bottom mirror)
			)
		)
		(property "Datasheet" "https://www.murata.com/products/productdetail?partno=GRM155R61H104KE14%23"
			(at 0 0 180)
			(layer "F.Fab")
			(hide yes)
			(effects
				(font
					(size 1.27 1.27)
					(thickness 0.15)
				)
			)
		)
		(property "Description" "SMD Multilayer Ceramic Capacitor, 0.1 µF, 50 V, 0402 [1005 Metric], ± 10%, X5R, GRM Series"
			(at 0 0 180)
			(layer "F.Fab")
			(hide yes)
			(effects
				(font
					(size 1.27 1.27)
					(thickness 0.15)
				)
			)
		)
		(property "Author" "Antmicro"
			(at 425.32 306 0)
			(layer "B.Fab")
			(hide yes)
			(effects
				(font
					(size 1 1)
					(thickness 0.15)
				)
				(justify mirror)
			)
		)
		(property "Dielectric" "X5R"
			(at 425.32 306 0)
			(layer "B.Fab")
			(hide yes)
			(effects
				(font
					(size 1 1)
					(thickness 0.15)
				)
				(justify mirror)
			)
		)
		(property "License" "Apache-2.0"
			(at 425.32 306 0)
			(layer "B.Fab")
			(hide yes)
			(effects
				(font
					(size 1 1)
					(thickness 0.15)
				)
				(justify mirror)
			)
		)
		(property "MPN" "GRM155R61H104KE14D"
			(at 425.32 306 0)
			(layer "B.Fab")
			(hide yes)
			(effects
				(font
					(size 1 1)
					(thickness 0.15)
				)
				(justify mirror)
			)
		)
		(property "Manufacturer" "Murata"
			(at 425.32 306 0)
			(layer "B.Fab")
			(hide yes)
			(effects
				(font
					(size 1 1)
					(thickness 0.15)
				)
				(justify mirror)
			)
		)
		(property "Public" ""
			(at 425.32 306 0)
			(layer "B.Fab")
			(hide yes)
			(effects
				(font
					(size 1 1)
					(thickness 0.15)
				)
				(justify mirror)
			)
		)
		(property "Val" "100n"
			(at 425.32 306 0)
			(layer "B.Fab")
			(hide yes)
			(effects
				(font
					(size 1 1)
					(thickness 0.15)
				)
				(justify mirror)
			)
		)
		(property "Voltage" "50V"
			(at 425.32 306 0)
			(layer "B.Fab")
			(hide yes)
			(effects
				(font
					(size 1 1)
					(thickness 0.15)
				)
				(justify mirror)
			)
		)
		(sheetname "/USB/")
		(sheetfile "usb.kicad_sch")
		(attr smd)
		(fp_rect
			(start -0.925 0.47)
			(end 0.925 -0.47)
			(stroke
				(width 0.05)
				(type default)
			)
			(fill no)
			(layer "B.CrtYd")
		)
		(fp_line
			(start 0.504 0.25)
			(end 0.504 -0.248)
			(stroke
				(width 0.15)
				(type solid)
			)
			(layer "B.Fab")
		)
		(fp_line
			(start 0.504 -0.248)
			(end -0.494 -0.248)
			(stroke
				(width 0.15)
				(type solid)
			)
			(layer "B.Fab")
		)
		(fp_line
			(start -0.494 0.25)
			(end 0.504 0.25)
			(stroke
				(width 0.15)
				(type solid)
			)
			(layer "B.Fab")
		)
		(fp_line
			(start -0.494 -0.248)
			(end -0.494 0.25)
			(stroke
				(width 0.15)
				(type solid)
			)
			(layer "B.Fab")
		)
		(fp_text user "Author: Antmicro"
			(at -0.939 -3.399 0)
			(layer "B.Fab")
			(effects
				(font
					(size 0.7 0.7)
					(thickness 0.15)
				)
				(justify left bottom mirror)
			)
		)
		(fp_text user "${REFERENCE}"
			(at -0.939 -4.599 0)
			(layer "B.Fab")
			(effects
				(font
					(size 0.7 0.7)
					(thickness 0.15)
				)
				(justify left bottom mirror)
			)
		)
		(fp_text user "License: Apache-2.0"
			(at -0.939 -5.799 0)
			(layer "B.Fab")
			(effects
				(font
					(size 0.7 0.7)
					(thickness 0.15)
				)
				(justify left bottom mirror)
			)
		)
		(pad "1" smd roundrect
			(at -0.48 0 180)
			(size 0.59 0.64)
			(layers "B.Cu" "B.Mask" "B.Paste")
			(roundrect_rratio 0.25)
			(net 417 "GND")
			(pintype "passive")
		)
		(pad "2" smd roundrect
			(at 0.48 0 180)
			(size 0.59 0.64)
			(layers "B.Cu" "B.Mask" "B.Paste")
			(roundrect_rratio 0.25)
			(net 50 "+3V3")
			(pintype "passive")
		)
	)
	(footprint "antmicro-footprints:R_0402_1005Metric"
		(layer "B.Cu")
		(at 199.95 121.7 -90)
		(descr "Resistor SMD 0402")
		(tags "resistor SMD 0402")
		(property "Reference" "R54"
			(at 2.2 0.375 90)
			(layer "B.SilkS")
			(effects
				(font
					(size 0.7 0.7)
					(thickness 0.15)
				)
				(justify left bottom mirror)
			)
		)
		(property "Value" "R_10k_0402"
			(at -1.011843 -1.772047 90)
			(layer "B.Fab")
			(hide yes)
			(effects
				(font
					(size 0.7 0.7)
					(thickness 0.15)
				)
				(justify left bottom mirror)
			)
		)
		(property "Datasheet" "https://www.bourns.com/docs/product-datasheets/cr.pdf"
			(at 0 0 270)
			(layer "F.Fab")
			(hide yes)
			(effects
				(font
					(size 1.27 1.27)
					(thickness 0.15)
				)
			)
		)
		(property "Description" "SMD Chip Resistor, 10 kohm, ± 1%, 62.5 mW, 0402 [1005 Metric], Thick Film, General Purpose"
			(at 0 0 270)
			(layer "F.Fab")
			(hide yes)
			(effects
				(font
					(size 1.27 1.27)
					(thickness 0.15)
				)
			)
		)
		(property "Author" "Antmicro"
			(at 78.25 321.65 0)
			(layer "B.Fab")
			(hide yes)
			(effects
				(font
					(size 1 1)
					(thickness 0.15)
				)
				(justify mirror)
			)
		)
		(property "License" "Apache-2.0"
			(at 78.25 321.65 0)
			(layer "B.Fab")
			(hide yes)
			(effects
				(font
					(size 1 1)
					(thickness 0.15)
				)
				(justify mirror)
			)
		)
		(property "MPN" "CR0402-FX-1002GLF"
			(at 78.25 321.65 0)
			(layer "B.Fab")
			(hide yes)
			(effects
				(font
					(size 1 1)
					(thickness 0.15)
				)
				(justify mirror)
			)
		)
		(property "Manufacturer" "Bourns"
			(at 78.25 321.65 0)
			(layer "B.Fab")
			(hide yes)
			(effects
				(font
					(size 1 1)
					(thickness 0.15)
				)
				(justify mirror)
			)
		)
		(property "Public" ""
			(at 78.25 321.65 0)
			(layer "B.Fab")
			(hide yes)
			(effects
				(font
					(size 1 1)
					(thickness 0.15)
				)
				(justify mirror)
			)
		)
		(property "Tolerance" "1%"
			(at 78.25 321.65 0)
			(layer "B.Fab")
			(hide yes)
			(effects
				(font
					(size 1 1)
					(thickness 0.15)
				)
				(justify mirror)
			)
		)
		(property "Val" "10k"
			(at 78.25 321.65 0)
			(layer "B.Fab")
			(hide yes)
			(effects
				(font
					(size 1 1)
					(thickness 0.15)
				)
				(justify mirror)
			)
		)
		(sheetname "/Memory/")
		(sheetfile "memory.kicad_sch")
		(attr smd)
		(fp_rect
			(start -0.925 0.47)
			(end 0.925 -0.47)
			(stroke
				(width 0.05)
				(type default)
			)
			(fill no)
			(layer "B.CrtYd")
		)
		(fp_rect
			(start -0.5 0.25)
			(end 0.5 -0.25)
			(stroke
				(width 0.15)
				(type solid)
			)
			(fill no)
			(layer "B.Fab")
		)
		(fp_text user "${REFERENCE}"
			(at -0.95 -3.168 90)
			(layer "B.Fab")
			(effects
				(font
					(size 0.7 0.7)
					(thickness 0.15)
				)
				(justify left bottom mirror)
			)
		)
		(fp_text user "Author: Antmicro"
			(at -0.95 -4.169 90)
			(layer "B.Fab")
			(effects
				(font
					(size 0.7 0.7)
					(thickness 0.15)
				)
				(justify left bottom mirror)
			)
		)
		(fp_text user "License: Apache-2.0"
			(at -0.95 -5.169 90)
			(layer "B.Fab")
			(effects
				(font
					(size 0.7 0.7)
					(thickness 0.15)
				)
				(justify left bottom mirror)
			)
		)
		(pad "1" smd roundrect
			(at -0.48 0 270)
			(size 0.59 0.64)
			(layers "B.Cu" "B.Mask" "B.Paste")
			(roundrect_rratio 0.25)
			(net 44 "SD_PWR_ON")
			(pintype "passive")
		)
		(pad "2" smd roundrect
			(at 0.48 0 270)
			(size 0.59 0.64)
			(layers "B.Cu" "B.Mask" "B.Paste")
			(roundrect_rratio 0.25)
			(net 137 "SD_VDD")
			(pintype "passive")
		)
	)
	(footprint "antmicro-footprints:C_0402_1005Metric"
		(layer "B.Cu")
		(at 198.94 134.73 90)
		(descr "Capacitor SMD 0402")
		(tags "capacitor SMD 0402")
		(property "Reference" "C32"
			(at 6.98 -9.565 270)
			(layer "B.SilkS")
			(effects
				(font
					(size 0.7 0.7)
					(thickness 0.15)
				)
				(justify left bottom mirror)
			)
		)
		(property "Value" "C_10n_0402"
			(at -1.022927 -2.155213 270)
			(layer "B.Fab")
			(hide yes)
			(effects
				(font
					(size 0.7 0.7)
					(thickness 0.15)
				)
				(justify left bottom mirror)
			)
		)
		(property "Datasheet" "https://www.murata.com/products/productdetail?partno=GRM155R71H103KA88%23"
			(at 0 0 90)
			(layer "F.Fab")
			(hide yes)
			(effects
				(font
					(size 1.27 1.27)
					(thickness 0.15)
				)
			)
		)
		(property "Description" "SMD Multilayer Ceramic Capacitor, 10000 pF, 50 V, 0402 [1005 Metric], ± 10%, X7R, GRM Series"
			(at 0 0 90)
			(layer "F.Fab")
			(hide yes)
			(effects
				(font
					(size 1.27 1.27)
					(thickness 0.15)
				)
			)
		)
		(property "Author" "Antmicro"
			(at 333.67 -64.21 0)
			(layer "B.Fab")
			(hide yes)
			(effects
				(font
					(size 1 1)
					(thickness 0.15)
				)
				(justify mirror)
			)
		)
		(property "Dielectric" "X7R"
			(at 333.67 -64.21 0)
			(layer "B.Fab")
			(hide yes)
			(effects
				(font
					(size 1 1)
					(thickness 0.15)
				)
				(justify mirror)
			)
		)
		(property "License" "Apache-2.0"
			(at 333.67 -64.21 0)
			(layer "B.Fab")
			(hide yes)
			(effects
				(font
					(size 1 1)
					(thickness 0.15)
				)
				(justify mirror)
			)
		)
		(property "MPN" "GRM155R71H103KA88D"
			(at 333.67 -64.21 0)
			(layer "B.Fab")
			(hide yes)
			(effects
				(font
					(size 1 1)
					(thickness 0.15)
				)
				(justify mirror)
			)
		)
		(property "Manufacturer" "Murata"
			(at 333.67 -64.21 0)
			(layer "B.Fab")
			(hide yes)
			(effects
				(font
					(size 1 1)
					(thickness 0.15)
				)
				(justify mirror)
			)
		)
		(property "Public" ""
			(at 333.67 -64.21 0)
			(layer "B.Fab")
			(hide yes)
			(effects
				(font
					(size 1 1)
					(thickness 0.15)
				)
				(justify mirror)
			)
		)
		(property "Val" "10n"
			(at 333.67 -64.21 0)
			(layer "B.Fab")
			(hide yes)
			(effects
				(font
					(size 1 1)
					(thickness 0.15)
				)
				(justify mirror)
			)
		)
		(property "Voltage" "50V"
			(at 333.67 -64.21 0)
			(layer "B.Fab")
			(hide yes)
			(effects
				(font
					(size 1 1)
					(thickness 0.15)
				)
				(justify mirror)
			)
		)
		(sheetname "/FPGA Supply/")
		(sheetfile "fpga-supply.kicad_sch")
		(attr smd)
		(fp_rect
			(start -0.925 0.47)
			(end 0.925 -0.47)
			(stroke
				(width 0.05)
				(type default)
			)
			(fill no)
			(layer "B.CrtYd")
		)
		(fp_line
			(start 0.504 -0.248)
			(end -0.494 -0.248)
			(stroke
				(width 0.15)
				(type solid)
			)
			(layer "B.Fab")
		)
		(fp_line
			(start -0.494 -0.248)
			(end -0.494 0.25)
			(stroke
				(width 0.15)
				(type solid)
			)
			(layer "B.Fab")
		)
		(fp_line
			(start 0.504 0.25)
			(end 0.504 -0.248)
			(stroke
				(width 0.15)
				(type solid)
			)
			(layer "B.Fab")
		)
		(fp_line
			(start -0.494 0.25)
			(end 0.504 0.25)
			(stroke
				(width 0.15)
				(type solid)
			)
			(layer "B.Fab")
		)
		(fp_text user "${REFERENCE}"
			(at -0.939 -4.599 270)
			(layer "B.Fab")
			(effects
				(font
					(size 0.7 0.7)
					(thickness 0.15)
				)
				(justify left bottom mirror)
			)
		)
		(fp_text user "License: Apache-2.0"
			(at -0.939 -5.799 270)
			(layer "B.Fab")
			(effects
				(font
					(size 0.7 0.7)
					(thickness 0.15)
				)
				(justify left bottom mirror)
			)
		)
		(fp_text user "Author: Antmicro"
			(at -0.939 -3.399 270)
			(layer "B.Fab")
			(effects
				(font
					(size 0.7 0.7)
					(thickness 0.15)
				)
				(justify left bottom mirror)
			)
		)
		(pad "1" smd roundrect
			(at -0.48 0 90)
			(size 0.59 0.64)
			(layers "B.Cu" "B.Mask" "B.Paste")
			(roundrect_rratio 0.25)
			(net 417 "GND")
			(pintype "passive")
		)
		(pad "2" smd roundrect
			(at 0.48 0 90)
			(size 0.59 0.64)
			(layers "B.Cu" "B.Mask" "B.Paste")
			(roundrect_rratio 0.25)
			(net 47 "+1V05")
			(pintype "passive")
		)
	)
	(footprint "antmicro-footprints:C_0402_1005Metric"
		(layer "B.Cu")
		(at 213.381 147.1 180)
		(descr "Capacitor SMD 0402")
		(tags "capacitor SMD 0402")
		(property "Reference" "C223"
			(at -1.219 -2.525 0)
			(layer "B.SilkS")
			(effects
				(font
					(size 0.7 0.7)
					(thickness 0.15)
				)
				(justify left bottom mirror)
			)
		)
		(property "Value" "C_100n_0402"
			(at -1.022927 -2.155213 0)
			(layer "B.Fab")
			(hide yes)
			(effects
				(font
					(size 0.7 0.7)
					(thickness 0.15)
				)
				(justify left bottom mirror)
			)
		)
		(property "Datasheet" "https://www.murata.com/products/productdetail?partno=GRM155R61H104KE14%23"
			(at 0 0 180)
			(layer "F.Fab")
			(hide yes)
			(effects
				(font
					(size 1.27 1.27)
					(thickness 0.15)
				)
			)
		)
		(property "Description" "SMD Multilayer Ceramic Capacitor, 0.1 µF, 50 V, 0402 [1005 Metric], ± 10%, X5R, GRM Series"
			(at 0 0 180)
			(layer "F.Fab")
			(hide yes)
			(effects
				(font
					(size 1.27 1.27)
					(thickness 0.15)
				)
			)
		)
		(property "Author" "Antmicro"
			(at 426.762 294.2 0)
			(layer "B.Fab")
			(hide yes)
			(effects
				(font
					(size 1 1)
					(thickness 0.15)
				)
				(justify mirror)
			)
		)
		(property "Dielectric" "X5R"
			(at 426.762 294.2 0)
			(layer "B.Fab")
			(hide yes)
			(effects
				(font
					(size 1 1)
					(thickness 0.15)
				)
				(justify mirror)
			)
		)
		(property "License" "Apache-2.0"
			(at 426.762 294.2 0)
			(layer "B.Fab")
			(hide yes)
			(effects
				(font
					(size 1 1)
					(thickness 0.15)
				)
				(justify mirror)
			)
		)
		(property "MPN" "GRM155R61H104KE14D"
			(at 426.762 294.2 0)
			(layer "B.Fab")
			(hide yes)
			(effects
				(font
					(size 1 1)
					(thickness 0.15)
				)
				(justify mirror)
			)
		)
		(property "Manufacturer" "Murata"
			(at 426.762 294.2 0)
			(layer "B.Fab")
			(hide yes)
			(effects
				(font
					(size 1 1)
					(thickness 0.15)
				)
				(justify mirror)
			)
		)
		(property "Public" ""
			(at 426.762 294.2 0)
			(layer "B.Fab")
			(hide yes)
			(effects
				(font
					(size 1 1)
					(thickness 0.15)
				)
				(justify mirror)
			)
		)
		(property "Val" "100n"
			(at 426.762 294.2 0)
			(layer "B.Fab")
			(hide yes)
			(effects
				(font
					(size 1 1)
					(thickness 0.15)
				)
				(justify mirror)
			)
		)
		(property "Voltage" "50V"
			(at 426.762 294.2 0)
			(layer "B.Fab")
			(hide yes)
			(effects
				(font
					(size 1 1)
					(thickness 0.15)
				)
				(justify mirror)
			)
		)
		(sheetname "/USB/")
		(sheetfile "usb.kicad_sch")
		(attr smd)
		(fp_rect
			(start -0.925 0.47)
			(end 0.925 -0.47)
			(stroke
				(width 0.05)
				(type default)
			)
			(fill no)
			(layer "B.CrtYd")
		)
		(fp_line
			(start 0.504 0.25)
			(end 0.504 -0.248)
			(stroke
				(width 0.15)
				(type solid)
			)
			(layer "B.Fab")
		)
		(fp_line
			(start 0.504 -0.248)
			(end -0.494 -0.248)
			(stroke
				(width 0.15)
				(type solid)
			)
			(layer "B.Fab")
		)
		(fp_line
			(start -0.494 0.25)
			(end 0.504 0.25)
			(stroke
				(width 0.15)
				(type solid)
			)
			(layer "B.Fab")
		)
		(fp_line
			(start -0.494 -0.248)
			(end -0.494 0.25)
			(stroke
				(width 0.15)
				(type solid)
			)
			(layer "B.Fab")
		)
		(fp_text user "Author: Antmicro"
			(at -0.939 -3.399 0)
			(layer "B.Fab")
			(effects
				(font
					(size 0.7 0.7)
					(thickness 0.15)
				)
				(justify left bottom mirror)
			)
		)
		(fp_text user "${REFERENCE}"
			(at -0.939 -4.599 0)
			(layer "B.Fab")
			(effects
				(font
					(size 0.7 0.7)
					(thickness 0.15)
				)
				(justify left bottom mirror)
			)
		)
		(fp_text user "License: Apache-2.0"
			(at -0.939 -5.799 0)
			(layer "B.Fab")
			(effects
				(font
					(size 0.7 0.7)
					(thickness 0.15)
				)
				(justify left bottom mirror)
			)
		)
		(pad "1" smd roundrect
			(at -0.48 0 180)
			(size 0.59 0.64)
			(layers "B.Cu" "B.Mask" "B.Paste")
			(roundrect_rratio 0.25)
			(net 417 "GND")
			(pintype "passive")
		)
		(pad "2" smd roundrect
			(at 0.48 0 180)
			(size 0.59 0.64)
			(layers "B.Cu" "B.Mask" "B.Paste")
			(roundrect_rratio 0.25)
			(net 50 "+3V3")
			(pintype "passive")
		)
	)
	(footprint "antmicro-footprints:TP_SMD_0.75mm"
		(layer "B.Cu")
		(at 182.9 143.4 180)
		(property "Reference" "TP20"
			(at -1.725 0.375 0)
			(layer "B.SilkS")
			(hide yes)
			(effects
				(font
					(size 0.7 0.7)
					(thickness 0.15)
				)
				(justify left bottom mirror)
			)
		)
		(property "Value" "TP_0.75mm_SMD"
			(at 0 -1.2 0)
			(layer "B.Fab")
			(hide yes)
			(effects
				(font
					(size 0.7 0.7)
					(thickness 0.15)
				)
				(justify left bottom mirror)
			)
		)
		(property "Description" "SMT test point"
			(at 0 0 0)
			(layer "B.Fab")
			(hide yes)
			(effects
				(font
					(size 1.27 1.27)
					(thickness 0.15)
				)
				(justify mirror)
			)
		)
		(property "MPN" ""
			(at 0 0 0)
			(unlocked yes)
			(layer "B.Fab")
			(hide yes)
			(effects
				(font
					(size 1 1)
					(thickness 0.15)
				)
				(justify mirror)
			)
		)
		(property "Manufacturer" ""
			(at 0 0 0)
			(unlocked yes)
			(layer "B.Fab")
			(hide yes)
			(effects
				(font
					(size 1 1)
					(thickness 0.15)
				)
				(justify mirror)
			)
		)
		(property "Author" "Antmicro"
			(at 0 0 0)
			(unlocked yes)
			(layer "B.Fab")
			(hide yes)
			(effects
				(font
					(size 1 1)
					(thickness 0.15)
				)
				(justify mirror)
			)
		)
		(property "License" "Apache-2.0"
			(at 0 0 0)
			(unlocked yes)
			(layer "B.Fab")
			(hide yes)
			(effects
				(font
					(size 1 1)
					(thickness 0.15)
				)
				(justify mirror)
			)
		)
		(property "Public" "False"
			(at 0 0 0)
			(unlocked yes)
			(layer "B.Fab")
			(hide yes)
			(effects
				(font
					(size 1 1)
					(thickness 0.15)
				)
				(justify mirror)
			)
		)
		(sheetname "/Supply/")
		(sheetfile "supply.kicad_sch")
		(attr exclude_from_pos_files exclude_from_bom)
		(fp_circle
			(center 0 0)
			(end 0.475 0)
			(stroke
				(width 0.05)
				(type default)
			)
			(fill no)
			(layer "B.CrtYd")
		)
		(fp_text user "Author: Antmicro"
			(at -0.4 -3.901 0)
			(layer "B.Fab")
			(effects
				(font
					(size 0.7 0.7)
					(thickness 0.15)
				)
				(justify left bottom mirror)
			)
		)
		(fp_text user "License: Apache-2.0"
			(at -0.4 -5.101 0)
			(layer "B.Fab")
			(effects
				(font
					(size 0.7 0.7)
					(thickness 0.15)
				)
				(justify left bottom mirror)
			)
		)
		(fp_text user "${REFERENCE}"
			(at -0.4 -2.7 0)
			(layer "B.Fab")
			(effects
				(font
					(size 0.7 0.7)
					(thickness 0.15)
				)
				(justify left bottom mirror)
			)
		)
		(pad "1" smd circle
			(at 0 0 180)
			(size 0.75 0.75)
			(layers "B.Cu" "B.Mask")
			(net 409 "/Supply/SENSE4_P")
			(pinfunction "1")
			(pintype "passive")
		)
	)
)
